(kicad_pcb
	(version 20211014)
	(generator pcbnew)
	(general
    (thickness 1.6)
  )
	(paper "A4")
	(title_block
    (title "SA800U (Snapdragon 845) Baseboard")
    (date "2023-10-19")
    (rev "1.0.3")
    (company "Antmicro Ltd.")
    (comment 1 "www.antmicro.com")
		(comment 9 "footprints 64-70 of 589")
	)
	(layers
    (0 "F.Cu" signal)
    (1 "In1.Cu" power)
    (2 "In2.Cu" signal)
    (3 "In3.Cu" signal)
    (4 "In4.Cu" power)
    (31 "B.Cu" signal)
    (32 "B.Adhes" user "B.Adhesive")
    (33 "F.Adhes" user "F.Adhesive")
    (34 "B.Paste" user)
    (35 "F.Paste" user)
    (36 "B.SilkS" user "B.Silkscreen")
    (37 "F.SilkS" user "F.Silkscreen")
    (38 "B.Mask" user)
    (39 "F.Mask" user)
    (40 "Dwgs.User" user "User.Drawings")
    (41 "Cmts.User" user "User.Comments")
    (42 "Eco1.User" user "User.Eco1")
    (43 "Eco2.User" user "User.Eco2")
    (44 "Edge.Cuts" user)
    (45 "Margin" user)
    (46 "B.CrtYd" user "B.Courtyard")
    (47 "F.CrtYd" user "F.Courtyard")
    (48 "B.Fab" user)
    (49 "F.Fab" user)
  )
	(footprint "sa800u-baseboard-hw-footprints:RJ45_5-2337992-8_Horizontal" locked (layer "F.Cu")
    (tedit 6215E152)
    (at 58.5 133.7)
    (property "Author" "Antmicro")
    (property "License" "Apache-2.0")
    (property "MPN" "5-2337992-8")
    (property "Manufacturer" "TE Connectivity")
    (property "Sheetfile" "ethernet-controller.kicad_sch")
    (property "Sheetname" "Ethernet Controller")
    (attr through_hole)
    (fp_text reference "J1" (at -2.2 -2.2) (layer "F.SilkS")
      (effects (font (size 0.7 0.7) (thickness 0.15)) (justify left bottom))
    )
    (fp_text value "Bus_RJ45_5-2337992-8" (at -2.6 22) (layer "F.Fab")
      (effects (font (size 0.7 0.7) (thickness 0.15)) (justify left bottom))
    )
    (fp_text user "License: Apache-2.0" (at -2.644 26.2) (layer "F.Fab") hide
      (effects (font (size 0.7 0.7) (thickness 0.15)) (justify left bottom))
    )
    (fp_text user "${REFERENCE}" (at -2.644 23.4) (layer "F.Fab") hide
      (effects (font (size 0.7 0.7) (thickness 0.15)) (justify left bottom))
    )
    (fp_text user "Author: Antmicro" (at -2.644 24.8) (layer "F.Fab") hide
      (effects (font (size 0.7 0.7) (thickness 0.15)) (justify left bottom))
    )
    (fp_line (start 13.791 4.48) (end 13.791 -1.845) (layer "F.SilkS") (width 0.15))
    (fp_line (start -2.363 -1.845) (end -2.363 4.48) (layer "F.SilkS") (width 0.15))
    (fp_line (start 13.791 -1.845) (end -2.363 -1.845) (layer "F.SilkS") (width 0.15))
    (fp_line (start 13.791 19.771) (end 13.791 7.217) (layer "F.SilkS") (width 0.15))
    (fp_line (start -2.363 19.771) (end 13.791 19.771) (layer "F.SilkS") (width 0.15))
    (fp_line (start -2.363 7.217) (end -2.363 19.771) (layer "F.SilkS") (width 0.15))
    (fp_rect (start -2.4 -1.8) (end 13.9 19.999) (layer "F.CrtYd") (width 0.05) (fill none))
    (fp_line (start 13.665 -1.718) (end -2.237 -1.718) (layer "F.Fab") (width 0.15))
    (fp_line (start -2.237 -1.718) (end -2.237 19.644) (layer "F.Fab") (width 0.15))
    (fp_line (start -2.237 19.644) (end 13.665 19.644) (layer "F.Fab") (width 0.15))
    (fp_line (start 13.665 19.644) (end 13.665 -1.718) (layer "F.Fab") (width 0.15))
    (pad "" np_thru_hole circle locked (at 0 8.9) (size 3.25 3.25) (drill 3.25) (layers *.Cu *.Mask))
    (pad "" np_thru_hole circle locked (at 11.429 8.9) (size 3.25 3.25) (drill 3.25) (layers *.Cu *.Mask))
    (pad "1" thru_hole circle locked (at 0 0) (size 1.397 1.397) (drill 0.889) (layers *.Cu *.Mask)
      (net 254 "/Ethernet Controller/LAN0_MDI0_N") (pinfunction "P1") (pintype "bidirectional"))
    (pad "2" thru_hole circle locked (at 1.269 2.539) (size 1.397 1.397) (drill 0.889) (layers *.Cu *.Mask)
      (net 255 "/Ethernet Controller/LAN0_MDI0_P") (pinfunction "P2") (pintype "bidirectional"))
    (pad "3" thru_hole circle locked (at 2.539 0) (size 1.397 1.397) (drill 0.889) (layers *.Cu *.Mask)
      (net 256 "/Ethernet Controller/LAN0_MDI1_N") (pinfunction "P3") (pintype "bidirectional"))
    (pad "4" thru_hole circle locked (at 3.809 2.539) (size 1.397 1.397) (drill 0.889) (layers *.Cu *.Mask)
      (net 63 "Net-(C16-Pad1)") (pinfunction "P4") (pintype "bidirectional"))
    (pad "5" thru_hole circle locked (at 5.078 0) (size 1.397 1.397) (drill 0.889) (layers *.Cu *.Mask)
      (net 63 "Net-(C16-Pad1)") (pinfunction "P5") (pintype "bidirectional"))
    (pad "6" thru_hole circle locked (at 6.349 2.539) (size 1.397 1.397) (drill 0.889) (layers *.Cu *.Mask)
      (net 257 "/Ethernet Controller/LAN0_MDI1_P") (pinfunction "P6") (pintype "bidirectional"))
    (pad "7" thru_hole circle locked (at 7.618 0) (size 1.397 1.397) (drill 0.889) (layers *.Cu *.Mask)
      (net 258 "/Ethernet Controller/LAN0_MDI2_N") (pinfunction "P7") (pintype "bidirectional"))
    (pad "8" thru_hole circle locked (at 8.89 2.539) (size 1.397 1.397) (drill 0.889) (layers *.Cu *.Mask)
      (net 259 "/Ethernet Controller/LAN0_MDI2_P") (pinfunction "P8") (pintype "bidirectional"))
    (pad "9" thru_hole circle locked (at 10.159 0) (size 1.397 1.397) (drill 0.889) (layers *.Cu *.Mask)
      (net 260 "/Ethernet Controller/LAN0_MDI3_N") (pinfunction "P9") (pintype "bidirectional"))
    (pad "10" thru_hole circle locked (at 11.429 2.539) (size 1.397 1.397) (drill 0.889) (layers *.Cu *.Mask)
      (net 261 "/Ethernet Controller/LAN0_MDI3_P") (pinfunction "P10") (pintype "bidirectional"))
    (pad "11" thru_hole circle locked (at 0 5.078) (size 1.397 1.397) (drill 0.889) (layers *.Cu *.Mask)
      (net 6 "PAIR12") (pinfunction "VC1") (pintype "bidirectional"))
    (pad "12" thru_hole circle locked (at 2.539 6.339) (size 1.397 1.397) (drill 0.889) (layers *.Cu *.Mask)
      (net 5 "PAIR36") (pinfunction "VC2") (pintype "bidirectional"))
    (pad "13" thru_hole circle locked (at 8.89 6.339) (size 1.397 1.397) (drill 0.889) (layers *.Cu *.Mask)
      (net 3 "PAIR45") (pinfunction "VC3") (pintype "bidirectional"))
    (pad "14" thru_hole circle locked (at 11.429 5.07) (size 1.397 1.397) (drill 0.889) (layers *.Cu *.Mask)
      (net 2 "PAIR78") (pinfunction "VC4") (pintype "bidirectional"))
    (pad "15" thru_hole circle locked (at -0.927 12.958) (size 1.524 1.524) (drill 1.016) (layers *.Cu *.Mask)
      (net 77 "Net-(J1-Pad15)") (pinfunction "LED_GRN+") (pintype "passive"))
    (pad "16" thru_hole circle locked (at 1.614 12.958) (size 1.524 1.524) (drill 1.016) (layers *.Cu *.Mask)
      (net 263 "/Ethernet Controller/ETH_LED2") (pinfunction "LED_GRN-") (pintype "passive"))
    (pad "17" thru_hole circle locked (at 9.814 12.958) (size 1.524 1.524) (drill 1.016) (layers *.Cu *.Mask)
      (net 78 "Net-(J1-Pad17)") (pinfunction "LED_YEL+") (pintype "passive"))
    (pad "18" thru_hole circle locked (at 12.355 12.958) (size 1.524 1.524) (drill 1.016) (layers *.Cu *.Mask)
      (net 262 "/Ethernet Controller/ETH_LED0") (pinfunction "LED_YEL-") (pintype "passive"))
    (pad "19" thru_hole circle locked (at -2.136 5.85) (size 2.1 2.1) (drill 1.6) (layers *.Cu *.Mask)
      (net 4 "Earth") (pinfunction "SHIELD") (pintype "passive"))
    (pad "20" thru_hole circle locked (at 13.563 5.85) (size 2.1082 2.1082) (drill 1.6002) (layers *.Cu *.Mask)
      (net 4 "Earth") (pinfunction "SHIELD") (pintype "passive"))
  )
	(footprint "sa800u-baseboard-hw-footprints:L_Murata_025020_0605Metric" (layer "F.Cu")
    (tedit 61AA2C4F)
    (at 152 130.5)
    (property "Author" "Antmicro")
    (property "License" "Apache-2.0")
    (property "MPN" "NFP0QHB242HS2D")
    (property "Manufacturer" "Murata")
    (property "Sheetfile" "lcm.kicad_sch")
    (property "Sheetname" "LCM")
    (attr smd)
    (fp_text reference "L15" (at -0.99 -0.72) (layer "F.SilkS")
      (effects (font (size 0.7 0.7) (thickness 0.15)) (justify left bottom))
    )
    (fp_text value "NFP0QHB242HS2D" (at 0 1.55) (layer "F.Fab")
      (effects (font (size 0.7 0.7) (thickness 0.15)) (justify left bottom))
    )
    (fp_text user "License: Apache-2.0" (at -1.027 5.805) (layer "F.Fab") hide
      (effects (font (size 0.7 0.7) (thickness 0.15)) (justify left bottom))
    )
    (fp_text user "${REFERENCE}" (at -1.027 3.406) (layer "F.Fab") hide
      (effects (font (size 0.7 0.7) (thickness 0.15)) (justify left bottom))
    )
    (fp_text user "Author: Antmicro" (at -1.027 4.605) (layer "F.Fab") hide
      (effects (font (size 0.7 0.7) (thickness 0.15)) (justify left bottom))
    )
    (fp_line (start -0.276 0.45) (end 0.276 0.45) (layer "F.SilkS") (width 0.15))
    (fp_line (start 0.276 -0.45) (end -0.276 -0.45) (layer "F.SilkS") (width 0.15))
    (fp_circle (center -0.5 -0.5) (end -0.449 -0.5) (layer "F.SilkS") (width 0.15) (fill solid))
    (fp_rect (start -0.5 -0.6) (end 0.5 0.6) (layer "F.CrtYd") (width 0.05) (fill none))
    (fp_line (start -0.277 0.349) (end 0.275 0.349) (layer "F.Fab") (width 0.15))
    (fp_line (start 0.275 -0.351) (end -0.277 -0.351) (layer "F.Fab") (width 0.15))
    (fp_line (start -0.277 -0.351) (end -0.277 0.349) (layer "F.Fab") (width 0.15))
    (fp_line (start 0.275 0.349) (end 0.275 -0.351) (layer "F.Fab") (width 0.15))
    (pad "1" smd rect (at -0.25 -0.24) (size 0.3 0.23) (layers "F.Cu" "F.Paste" "F.Mask")
      (net 310 "/LCM/DSI_CLK_L_N") (pinfunction "1") (pintype "passive"))
    (pad "2" smd rect (at 0.248 -0.24) (size 0.3 0.23) (layers "F.Cu" "F.Paste" "F.Mask")
      (net 86 "DSI0_CLK_N") (pinfunction "2") (pintype "passive"))
    (pad "3" smd rect (at 0.248 0.239) (size 0.3 0.23) (layers "F.Cu" "F.Paste" "F.Mask")
      (net 85 "DSI0_CLK_P") (pinfunction "3") (pintype "passive"))
    (pad "4" smd rect (at -0.25 0.239) (size 0.3 0.23) (layers "F.Cu" "F.Paste" "F.Mask")
      (net 309 "/LCM/DSI_CLK_L_P") (pinfunction "4") (pintype "passive"))
  )
	(footprint "sa800u-baseboard-hw-footprints:L_Murata_025020_0605Metric" (layer "F.Cu")
    (tedit 61AA2C4F)
    (at 152 127.5)
    (property "Author" "Antmicro")
    (property "License" "Apache-2.0")
    (property "MPN" "NFP0QHB242HS2D")
    (property "Manufacturer" "Murata")
    (property "Sheetfile" "lcm.kicad_sch")
    (property "Sheetname" "LCM")
    (attr smd)
    (fp_text reference "L14" (at -0.99 -0.72) (layer "F.SilkS")
      (effects (font (size 0.7 0.7) (thickness 0.15)) (justify left bottom))
    )
    (fp_text value "NFP0QHB242HS2D" (at 0 1.55) (layer "F.Fab")
      (effects (font (size 0.7 0.7) (thickness 0.15)) (justify left bottom))
    )
    (fp_text user "License: Apache-2.0" (at -1.027 5.805) (layer "F.Fab") hide
      (effects (font (size 0.7 0.7) (thickness 0.15)) (justify left bottom))
    )
    (fp_text user "Author: Antmicro" (at -1.027 4.605) (layer "F.Fab") hide
      (effects (font (size 0.7 0.7) (thickness 0.15)) (justify left bottom))
    )
    (fp_text user "${REFERENCE}" (at -1.027 3.406) (layer "F.Fab") hide
      (effects (font (size 0.7 0.7) (thickness 0.15)) (justify left bottom))
    )
    (fp_line (start -0.276 0.45) (end 0.276 0.45) (layer "F.SilkS") (width 0.15))
    (fp_line (start 0.276 -0.45) (end -0.276 -0.45) (layer "F.SilkS") (width 0.15))
    (fp_circle (center -0.5 -0.5) (end -0.449 -0.5) (layer "F.SilkS") (width 0.15) (fill solid))
    (fp_rect (start -0.5 -0.6) (end 0.5 0.6) (layer "F.CrtYd") (width 0.05) (fill none))
    (fp_line (start 0.275 0.349) (end 0.275 -0.351) (layer "F.Fab") (width 0.15))
    (fp_line (start -0.277 -0.351) (end -0.277 0.349) (layer "F.Fab") (width 0.15))
    (fp_line (start -0.277 0.349) (end 0.275 0.349) (layer "F.Fab") (width 0.15))
    (fp_line (start 0.275 -0.351) (end -0.277 -0.351) (layer "F.Fab") (width 0.15))
    (pad "1" smd rect (at -0.25 -0.24) (size 0.3 0.23) (layers "F.Cu" "F.Paste" "F.Mask")
      (net 312 "/LCM/DSI_LN0_L_N") (pinfunction "1") (pintype "passive"))
    (pad "2" smd rect (at 0.248 -0.24) (size 0.3 0.23) (layers "F.Cu" "F.Paste" "F.Mask")
      (net 87 "DSI0_LN0_N") (pinfunction "2") (pintype "passive"))
    (pad "3" smd rect (at 0.248 0.239) (size 0.3 0.23) (layers "F.Cu" "F.Paste" "F.Mask")
      (net 88 "DSI0_LN0_P") (pinfunction "3") (pintype "passive"))
    (pad "4" smd rect (at -0.25 0.239) (size 0.3 0.23) (layers "F.Cu" "F.Paste" "F.Mask")
      (net 311 "/LCM/DSI_LN0_L_P") (pinfunction "4") (pintype "passive"))
  )
	(footprint "sa800u-baseboard-hw-footprints:L_Murata_025020_0605Metric" (layer "F.Cu")
    (tedit 61AA2C4F)
    (at 152 124.5)
    (property "Author" "Antmicro")
    (property "License" "Apache-2.0")
    (property "MPN" "NFP0QHB242HS2D")
    (property "Manufacturer" "Murata")
    (property "Sheetfile" "lcm.kicad_sch")
    (property "Sheetname" "LCM")
    (attr smd)
    (fp_text reference "L13" (at -0.99 -0.72) (layer "F.SilkS")
      (effects (font (size 0.7 0.7) (thickness 0.15)) (justify left bottom))
    )
    (fp_text value "NFP0QHB242HS2D" (at 0 1.55) (layer "F.Fab")
      (effects (font (size 0.7 0.7) (thickness 0.15)) (justify left bottom))
    )
    (fp_text user "${REFERENCE}" (at -1.027 3.406) (layer "F.Fab") hide
      (effects (font (size 0.7 0.7) (thickness 0.15)) (justify left bottom))
    )
    (fp_text user "License: Apache-2.0" (at -1.027 5.805) (layer "F.Fab") hide
      (effects (font (size 0.7 0.7) (thickness 0.15)) (justify left bottom))
    )
    (fp_text user "Author: Antmicro" (at -1.027 4.605) (layer "F.Fab") hide
      (effects (font (size 0.7 0.7) (thickness 0.15)) (justify left bottom))
    )
    (fp_line (start -0.276 0.45) (end 0.276 0.45) (layer "F.SilkS") (width 0.15))
    (fp_line (start 0.276 -0.45) (end -0.276 -0.45) (layer "F.SilkS") (width 0.15))
    (fp_circle (center -0.5 -0.5) (end -0.449 -0.5) (layer "F.SilkS") (width 0.15) (fill solid))
    (fp_rect (start -0.5 -0.6) (end 0.5 0.6) (layer "F.CrtYd") (width 0.05) (fill none))
    (fp_line (start -0.277 -0.351) (end -0.277 0.349) (layer "F.Fab") (width 0.15))
    (fp_line (start -0.277 0.349) (end 0.275 0.349) (layer "F.Fab") (width 0.15))
    (fp_line (start 0.275 -0.351) (end -0.277 -0.351) (layer "F.Fab") (width 0.15))
    (fp_line (start 0.275 0.349) (end 0.275 -0.351) (layer "F.Fab") (width 0.15))
    (pad "1" smd rect (at -0.25 -0.24) (size 0.3 0.23) (layers "F.Cu" "F.Paste" "F.Mask")
      (net 314 "/LCM/DSI_LN1_L_N") (pinfunction "1") (pintype "passive"))
    (pad "2" smd rect (at 0.248 -0.24) (size 0.3 0.23) (layers "F.Cu" "F.Paste" "F.Mask")
      (net 83 "DSI0_LN1_N") (pinfunction "2") (pintype "passive"))
    (pad "3" smd rect (at 0.248 0.239) (size 0.3 0.23) (layers "F.Cu" "F.Paste" "F.Mask")
      (net 84 "DSI0_LN1_P") (pinfunction "3") (pintype "passive"))
    (pad "4" smd rect (at -0.25 0.239) (size 0.3 0.23) (layers "F.Cu" "F.Paste" "F.Mask")
      (net 313 "/LCM/DSI_LN1_L_P") (pinfunction "4") (pintype "passive"))
  )
	(footprint "sa800u-baseboard-hw-footprints:R_0402_1005Metric" (layer "F.Cu")
    (tedit 5FD9C158)
    (at 148.3 142.5 -90)
    (descr "Resistor SMD 0402")
    (tags "resistor SMD 0402")
    (property "Author" "Antmicro")
    (property "Current" "1A")
    (property "License" "Apache-2.0")
    (property "MPN" "ERJ2GE0R00X")
    (property "Manufacturer" "Panasonic")
    (property "Sheetfile" "hdmi-converter.kicad_sch")
    (property "Sheetname" "HDMI converter")
    (property "Tolerance" "")
    (property "Val" "0R")
    (attr smd)
    (fp_text reference "R30" (at 0.96 0.58 -90) (layer "F.SilkS")
      (effects (font (size 0.7 0.7) (thickness 0.15)) (justify left bottom))
    )
    (fp_text value "R_0R_0402" (at 0 1.4 -90) (layer "F.Fab")
      (effects (font (size 0.7 0.7) (thickness 0.15)) (justify left bottom))
    )
    (fp_text user "License: Apache-2.0" (at -0.95 5.169 -90) (layer "F.Fab") hide
      (effects (font (size 0.7 0.7) (thickness 0.15)) (justify left bottom))
    )
    (fp_text user "Author: Antmicro" (at -0.95 4.169 -90) (layer "F.Fab") hide
      (effects (font (size 0.7 0.7) (thickness 0.15)) (justify left bottom))
    )
    (fp_text user "${REFERENCE}" (at -0.95 3.168 -90) (layer "F.Fab") hide
      (effects (font (size 0.7 0.7) (thickness 0.15)) (justify left bottom))
    )
    (fp_rect (start -0.93 -0.47) (end 0.93 0.47) (layer "F.CrtYd") (width 0.05) (fill none))
    (fp_rect (start -0.5 -0.25) (end 0.5 0.25) (layer "F.Fab") (width 0.15) (fill none))
    (pad "1" smd roundrect (at -0.485 0 270) (size 0.59 0.64) (layers "F.Cu" "F.Paste" "F.Mask") (roundrect_rratio 0.25)
      (net 395 "Net-(R27-Pad1)") (pintype "passive"))
    (pad "2" smd roundrect (at 0.485 0 270) (size 0.59 0.64) (layers "F.Cu" "F.Paste" "F.Mask") (roundrect_rratio 0.25)
      (net 234 "/HDMI converter/HDMI_DETECT") (pintype "passive"))
  )
	(footprint "sa800u-baseboard-hw-footprints:C_0603_1608Metric" (layer "F.Cu")
    (tedit 5D5E94D2)
    (at 83.2 141.1 -90)
    (descr "Capacitor SMD 0603")
    (tags "capacitor 0603")
    (property "Author" "Antmicro")
    (property "Dielectric" "")
    (property "License" "Apache-2.0")
    (property "MPN" "0603YD105KAT2A")
    (property "Manufacturer" "Walsin")
    (property "Sheetfile" "usb-pd.kicad_sch")
    (property "Sheetname" "USB-PD")
    (property "Val" "1u")
    (property "Voltage" "")
    (attr smd)
    (fp_text reference "C153" (at 1.21 -0.64) (layer "F.SilkS")
      (effects (font (size 0.7 0.7) (thickness 0.15)) (justify left bottom))
    )
    (fp_text value "C_1u_0603" (at 0 1.6 -90) (layer "F.Fab")
      (effects (font (size 0.7 0.7) (thickness 0.15)) (justify left bottom))
    )
    (fp_text user "License: Apache-2.0" (at -1.682 5.895 -90) (layer "F.Fab") hide
      (effects (font (size 0.7 0.7) (thickness 0.15)) (justify left bottom))
    )
    (fp_text user "${REFERENCE}" (at -1.682 3.895 -90) (layer "F.Fab") hide
      (effects (font (size 0.7 0.7) (thickness 0.15)) (justify left bottom))
    )
    (fp_text user "Author: Antmicro" (at -1.682 4.894 -90) (layer "F.Fab") hide
      (effects (font (size 0.7 0.7) (thickness 0.15)) (justify left bottom))
    )
    (fp_line (start -0.3 0.3) (end 0.3 0.3) (layer "F.SilkS") (width 0.15))
    (fp_line (start -0.3 -0.3) (end 0.3 -0.3) (layer "F.SilkS") (width 0.15))
    (fp_rect (start -1.24 -0.7) (end 1.24 0.7) (layer "F.CrtYd") (width 0.05) (fill none))
    (fp_rect (start -0.8 -0.4) (end 0.8 0.4) (layer "F.Fab") (width 0.15) (fill none))
    (pad "1" smd roundrect (at -0.7 0 270) (size 0.6 0.8) (layers "F.Cu" "F.Paste" "F.Mask") (roundrect_rratio 0.2)
      (net 364 "Net-(C153-Pad1)") (pintype "passive"))
    (pad "2" smd roundrect (at 0.7 0 270) (size 0.6 0.8) (layers "F.Cu" "F.Paste" "F.Mask") (roundrect_rratio 0.2)
      (net 1 "GND") (pintype "passive"))
  )
	(footprint "sa800u-baseboard-hw-footprints:R_0402_1005Metric" (layer "F.Cu")
    (tedit 5FD9C158)
    (at 83.4 139.3)
    (descr "Resistor SMD 0402")
    (tags "resistor SMD 0402")
    (property "Author" "Antmicro")
    (property "License" "Apache-2.0")
    (property "MPN" "CR0402-FX-1001GLF")
    (property "Manufacturer" "Bourns")
    (property "Sheetfile" "usb-pd.kicad_sch")
    (property "Sheetname" "USB-PD")
    (property "Tolerance" "1%")
    (property "Val" "1k")
    (attr smd)
    (fp_text reference "R159" (at 0.34 1.48) (layer "F.SilkS")
      (effects (font (size 0.7 0.7) (thickness 0.15)) (justify left bottom))
    )
    (fp_text value "R_1k_0402" (at 0 1.4) (layer "F.Fab")
      (effects (font (size 0.7 0.7) (thickness 0.15)) (justify left bottom))
    )
    (fp_text user "License: Apache-2.0" (at -0.95 5.169) (layer "F.Fab") hide
      (effects (font (size 0.7 0.7) (thickness 0.15)) (justify left bottom))
    )
    (fp_text user "${REFERENCE}" (at -0.95 3.168) (layer "F.Fab") hide
      (effects (font (size 0.7 0.7) (thickness 0.15)) (justify left bottom))
    )
    (fp_text user "Author: Antmicro" (at -0.95 4.169) (layer "F.Fab") hide
      (effects (font (size 0.7 0.7) (thickness 0.15)) (justify left bottom))
    )
    (fp_rect (start -0.93 -0.47) (end 0.93 0.47) (layer "F.CrtYd") (width 0.05) (fill none))
    (fp_rect (start -0.5 -0.25) (end 0.5 0.25) (layer "F.Fab") (width 0.15) (fill none))
    (pad "1" smd roundrect (at -0.485 0) (size 0.59 0.64) (layers "F.Cu" "F.Paste" "F.Mask") (roundrect_rratio 0.25)
      (net 364 "Net-(C153-Pad1)") (pintype "passive"))
    (pad "2" smd roundrect (at 0.485 0) (size 0.59 0.64) (layers "F.Cu" "F.Paste" "F.Mask") (roundrect_rratio 0.25)
      (net 466 "/USB-PD/VS_DISCH") (pintype "passive"))
  )
)
